# S9S_MB_2U (Grand Teton) — schematic netlist excerpt (pin names and nets, part order shuffled) for the footprints in the layout excerpt that follows; sources: Cadence DE-HDL packaged netlist, KiCad conversion of 03242023_DA0F0TMBIJ0_F0T_Motherboard_J_brd_V01_OCP.brd

PC2238  Q_CAP  0.1UF 25V 10% X7R  pkg 0402  page 242 : A = P12V_SCM_R ; B = GND
PC2188  Q_CAP  1UF 25V 10% X6S  pkg C0402  page 301 : A = P12V_PSU ; B = GND

(kicad_pcb
	(version 20260206)
	(generator "pcbnew")
	(generator_version "10.0")
	(general
		(thickness 1.6)
		(legacy_teardrops no)
	)
	(paper "A4")
	(title_block
		(title "03242023_DA0F0TMBIJ0_F0T_Motherboard_J_brd_V01_OCP.brd")
		(comment 1 "Grand Teton / footprints 183-184 of 6105")
	)
	(layers
		(0 "F.Cu" signal "TOP")
		(4 "In1.Cu" signal "GND")
		(6 "In2.Cu" signal "IN1")
		(8 "In3.Cu" signal "GND1")
		(10 "In4.Cu" signal "IN2")
		(12 "In5.Cu" signal "GND2")
		(14 "In6.Cu" signal "IN3")
		(16 "In7.Cu" signal "GND3")
		(18 "In8.Cu" signal "VCC")
		(20 "In9.Cu" signal "VCC1")
		(22 "In10.Cu" signal "GND4")
		(24 "In11.Cu" signal "IN4")
		(26 "In12.Cu" signal "GND5")
		(28 "In13.Cu" signal "IN5")
		(30 "In14.Cu" signal "GND6")
		(32 "In15.Cu" signal "IN6")
		(34 "In16.Cu" signal "GND7")
		(2 "B.Cu" signal "BOTTOM")
		(9 "F.Adhes" user "F.Adhesive")
		(11 "B.Adhes" user "B.Adhesive")
		(13 "F.Paste" user "Package Geometry/Pastemask Top")
		(15 "B.Paste" user "Package Geometry/Pastemask Bottom")
		(5 "F.SilkS" user "Ref Des/Silkscreen Top")
		(7 "B.SilkS" user "Ref Des/Silkscreen Bottom")
		(1 "F.Mask" user "Board Geometry/Soldermask Top")
		(3 "B.Mask" user "Board Geometry/Soldermask Bottom")
		(17 "Dwgs.User" user "User.Drawings")
		(19 "Cmts.User" user "User.Comments")
		(21 "Eco1.User" user "User.Eco1")
		(23 "Eco2.User" user "User.Eco2")
		(25 "Edge.Cuts" user "Board Geometry/Outline")
		(27 "Margin" user)
		(31 "F.CrtYd" user "Package Geometry/Place Bound Top")
		(29 "B.CrtYd" user "Package Geometry/Place Bound Bottom")
		(35 "F.Fab" user "Ref Des/Assembly Top")
		(33 "B.Fab" user "Ref Des/Assembly Bottom")
	)
	(footprint ""
		(layer "F.Cu")
		(at 185.255662 -410.083762 180)
		(property "Reference" "PC2188"
			(at 0 0 180)
			(layer "F.SilkS")
			(hide yes)
			(effects
				(font
					(size 1.27 1.27)
				)
			)
		)
		(property "Value" ""
			(at 0 0 180)
			(layer "F.Fab")
			(effects
				(font
					(size 1.27 1.27)
				)
			)
		)
		(duplicate_pad_numbers_are_jumpers no)
		(fp_line
			(start 0.7874 0.4064)
			(end -0.7874 0.4064)
			(stroke
				(width 0.1524)
				(type default)
			)
			(layer "F.SilkS")
		)
		(fp_line
			(start 0.7874 -0.4064)
			(end 0.7874 0.4064)
			(stroke
				(width 0.1524)
				(type default)
			)
			(layer "F.SilkS")
		)
		(fp_line
			(start -0.7874 0.4064)
			(end -0.7874 -0.4064)
			(stroke
				(width 0.1524)
				(type default)
			)
			(layer "F.SilkS")
		)
		(fp_line
			(start -0.7874 -0.4064)
			(end 0.7874 -0.4064)
			(stroke
				(width 0.1524)
				(type default)
			)
			(layer "F.SilkS")
		)
		(fp_line
			(start 0.67945 0.3048)
			(end 0.120396 0.3048)
			(stroke
				(width 0.1)
				(type default)
			)
			(layer "F.Fab")
		)
		(fp_line
			(start 0.67945 -0.3048)
			(end 0.67945 0.3048)
			(stroke
				(width 0.1)
				(type default)
			)
			(layer "F.Fab")
		)
		(fp_line
			(start 0.12065 -0.2794)
			(end 0.12065 -0.3048)
			(stroke
				(width 0.1)
				(type default)
			)
			(layer "F.Fab")
		)
		(fp_line
			(start 0.12065 -0.3048)
			(end 0.67945 -0.3048)
			(stroke
				(width 0.1)
				(type default)
			)
			(layer "F.Fab")
		)
		(fp_line
			(start 0.120396 0.3048)
			(end 0.120396 0.2794)
			(stroke
				(width 0.1)
				(type default)
			)
			(layer "F.Fab")
		)
		(fp_line
			(start 0.120396 0.2794)
			(end -0.12065 0.2794)
			(stroke
				(width 0.1)
				(type default)
			)
			(layer "F.Fab")
		)
		(fp_line
			(start -0.12065 0.3048)
			(end -0.67945 0.3048)
			(stroke
				(width 0.1)
				(type default)
			)
			(layer "F.Fab")
		)
		(fp_line
			(start -0.12065 0.2794)
			(end -0.12065 0.3048)
			(stroke
				(width 0.1)
				(type default)
			)
			(layer "F.Fab")
		)
		(fp_line
			(start -0.12065 -0.2794)
			(end 0.12065 -0.2794)
			(stroke
				(width 0.1)
				(type default)
			)
			(layer "F.Fab")
		)
		(fp_line
			(start -0.12065 -0.305054)
			(end -0.12065 -0.2794)
			(stroke
				(width 0.1)
				(type default)
			)
			(layer "F.Fab")
		)
		(fp_line
			(start -0.67945 0.3048)
			(end -0.67945 -0.305054)
			(stroke
				(width 0.1)
				(type default)
			)
			(layer "F.Fab")
		)
		(fp_line
			(start -0.67945 -0.305054)
			(end -0.12065 -0.305054)
			(stroke
				(width 0.1)
				(type default)
			)
			(layer "F.Fab")
		)
		(pad "1" smd circle
			(at -0.40005 0 180)
			(size 0 0)
			(layers "F.Cu" "F.Mask" "F.Paste")
			(net "P12V_PSU")
		)
		(pad "2" smd circle
			(at 0.40005 0 180)
			(size 0 0)
			(layers "F.Cu" "F.Mask" "F.Paste")
			(net "GND")
		)
	)
	(footprint ""
		(layer "F.Cu")
		(at 175.82388 -19.548348 180)
		(property "Reference" "PC2238"
			(at 0 0 180)
			(layer "F.SilkS")
			(hide yes)
			(effects
				(font
					(size 1.27 1.27)
				)
			)
		)
		(property "Value" ""
			(at 0 0 180)
			(layer "F.Fab")
			(effects
				(font
					(size 1.27 1.27)
				)
			)
		)
		(duplicate_pad_numbers_are_jumpers no)
		(fp_line
			(start 0.7874 0.4064)
			(end -0.7874 0.4064)
			(stroke
				(width 0.1524)
				(type default)
			)
			(layer "F.SilkS")
		)
		(fp_line
			(start 0.7874 -0.4064)
			(end 0.7874 0.4064)
			(stroke
				(width 0.1524)
				(type default)
			)
			(layer "F.SilkS")
		)
		(fp_line
			(start -0.7874 0.4064)
			(end -0.7874 -0.4064)
			(stroke
				(width 0.1524)
				(type default)
			)
			(layer "F.SilkS")
		)
		(fp_line
			(start -0.7874 -0.4064)
			(end 0.7874 -0.4064)
			(stroke
				(width 0.1524)
				(type default)
			)
			(layer "F.SilkS")
		)
		(fp_line
			(start 0.67945 0.3048)
			(end 0.120396 0.3048)
			(stroke
				(width 0.1)
				(type default)
			)
			(layer "F.Fab")
		)
		(fp_line
			(start 0.67945 -0.3048)
			(end 0.67945 0.3048)
			(stroke
				(width 0.1)
				(type default)
			)
			(layer "F.Fab")
		)
		(fp_line
			(start 0.12065 -0.2794)
			(end 0.12065 -0.3048)
			(stroke
				(width 0.1)
				(type default)
			)
			(layer "F.Fab")
		)
		(fp_line
			(start 0.12065 -0.3048)
			(end 0.67945 -0.3048)
			(stroke
				(width 0.1)
				(type default)
			)
			(layer "F.Fab")
		)
		(fp_line
			(start 0.120396 0.3048)
			(end 0.120396 0.2794)
			(stroke
				(width 0.1)
				(type default)
			)
			(layer "F.Fab")
		)
		(fp_line
			(start 0.120396 0.2794)
			(end -0.12065 0.2794)
			(stroke
				(width 0.1)
				(type default)
			)
			(layer "F.Fab")
		)
		(fp_line
			(start -0.12065 0.3048)
			(end -0.67945 0.3048)
			(stroke
				(width 0.1)
				(type default)
			)
			(layer "F.Fab")
		)
		(fp_line
			(start -0.12065 0.2794)
			(end -0.12065 0.3048)
			(stroke
				(width 0.1)
				(type default)
			)
			(layer "F.Fab")
		)
		(fp_line
			(start -0.12065 -0.2794)
			(end 0.12065 -0.2794)
			(stroke
				(width 0.1)
				(type default)
			)
			(layer "F.Fab")
		)
		(fp_line
			(start -0.12065 -0.305054)
			(end -0.12065 -0.2794)
			(stroke
				(width 0.1)
				(type default)
			)
			(layer "F.Fab")
		)
		(fp_line
			(start -0.67945 0.3048)
			(end -0.67945 -0.305054)
			(stroke
				(width 0.1)
				(type default)
			)
			(layer "F.Fab")
		)
		(fp_line
			(start -0.67945 -0.305054)
			(end -0.12065 -0.305054)
			(stroke
				(width 0.1)
				(type default)
			)
			(layer "F.Fab")
		)
		(pad "1" smd circle
			(at -0.40005 0 180)
			(size 0 0)
			(layers "F.Cu" "F.Mask" "F.Paste")
			(net "P12V_SCM_R")
		)
		(pad "2" smd circle
			(at 0.40005 0 180)
			(size 0 0)
			(layers "F.Cu" "F.Mask" "F.Paste")
			(net "GND")
		)
	)
)
